# S9S_MB_2U (Grand Teton) — schematic netlist excerpt (pin names and nets, part order shuffled) for the footprints in the layout excerpt that follows; sources: Cadence DE-HDL packaged netlist, KiCad conversion of 03242023_DA0F0TMBIJ0_F0T_Motherboard_J_brd_V01_OCP.brd

R3668  Q_RES  1K 1% CHIP  pkg 0402LF  page 250 : A = ADC128_A1 ; B = GND

U278  74LVC1G08W57  74LVC1G08W5-7 IC  pkg SOT25-5_0-95_3X1-6  page 246
  A  = FM_GPU_HSC_EN
  B  = GPU_PRSNT_R
  GND  = GND
  Y  = FM_GPU_HSC_EN_BUF_R
  VCC  = P3V3_AUX

(kicad_pcb
	(version 20260206)
	(generator "pcbnew")
	(generator_version "10.0")
	(general
		(thickness 1.6)
		(legacy_teardrops no)
	)
	(paper "A4")
	(title_block
		(title "03242023_DA0F0TMBIJ0_F0T_Motherboard_J_brd_V01_OCP.brd")
		(comment 1 "Grand Teton / footprints 1602-1603 of 6105")
	)
	(layers
		(0 "F.Cu" signal "TOP")
		(4 "In1.Cu" signal "GND")
		(6 "In2.Cu" signal "IN1")
		(8 "In3.Cu" signal "GND1")
		(10 "In4.Cu" signal "IN2")
		(12 "In5.Cu" signal "GND2")
		(14 "In6.Cu" signal "IN3")
		(16 "In7.Cu" signal "GND3")
		(18 "In8.Cu" signal "VCC")
		(20 "In9.Cu" signal "VCC1")
		(22 "In10.Cu" signal "GND4")
		(24 "In11.Cu" signal "IN4")
		(26 "In12.Cu" signal "GND5")
		(28 "In13.Cu" signal "IN5")
		(30 "In14.Cu" signal "GND6")
		(32 "In15.Cu" signal "IN6")
		(34 "In16.Cu" signal "GND7")
		(2 "B.Cu" signal "BOTTOM")
		(9 "F.Adhes" user "F.Adhesive")
		(11 "B.Adhes" user "B.Adhesive")
		(13 "F.Paste" user "Package Geometry/Pastemask Top")
		(15 "B.Paste" user "Package Geometry/Pastemask Bottom")
		(5 "F.SilkS" user "Ref Des/Silkscreen Top")
		(7 "B.SilkS" user "Ref Des/Silkscreen Bottom")
		(1 "F.Mask" user "Board Geometry/Soldermask Top")
		(3 "B.Mask" user "Board Geometry/Soldermask Bottom")
		(17 "Dwgs.User" user "User.Drawings")
		(19 "Cmts.User" user "User.Comments")
		(21 "Eco1.User" user "User.Eco1")
		(23 "Eco2.User" user "User.Eco2")
		(25 "Edge.Cuts" user "Board Geometry/Outline")
		(27 "Margin" user)
		(31 "F.CrtYd" user "Package Geometry/Place Bound Top")
		(29 "B.CrtYd" user "Package Geometry/Place Bound Bottom")
		(35 "F.Fab" user "Ref Des/Assembly Top")
		(33 "B.Fab" user "Ref Des/Assembly Bottom")
	)
	(footprint ""
		(layer "F.Cu")
		(at 192.601342 -433.96916 -90)
		(property "Reference" "U278"
			(at 1.21412 -2.605532 90)
			(unlocked yes)
			(layer "F.SilkS")
			(effects
				(font
					(size 0.7874 0.5842)
					(thickness 0.1524)
				)
				(justify left)
			)
		)
		(property "Value" ""
			(at 0 0 270)
			(layer "F.Fab")
			(effects
				(font
					(size 1.27 1.27)
				)
			)
		)
		(duplicate_pad_numbers_are_jumpers no)
		(fp_line
			(start -1.733296 1.549908)
			(end 1.733296 1.549908)
			(stroke
				(width 0.1524)
				(type default)
			)
			(layer "F.SilkS")
		)
		(fp_line
			(start 1.733296 1.549908)
			(end 1.733296 -1.549908)
			(stroke
				(width 0.1524)
				(type default)
			)
			(layer "F.SilkS")
		)
		(fp_line
			(start 0 -0.889)
			(end -0.660908 -1.549908)
			(stroke
				(width 0.1524)
				(type default)
			)
			(layer "F.SilkS")
		)
		(fp_line
			(start -1.733296 -1.549908)
			(end -1.733296 1.549908)
			(stroke
				(width 0.1524)
				(type default)
			)
			(layer "F.SilkS")
		)
		(fp_line
			(start -0.660908 -1.549908)
			(end -1.733296 -1.549908)
			(stroke
				(width 0.1524)
				(type default)
			)
			(layer "F.SilkS")
		)
		(fp_line
			(start 0.660908 -1.549908)
			(end 0 -0.889)
			(stroke
				(width 0.1524)
				(type default)
			)
			(layer "F.SilkS")
		)
		(fp_line
			(start 1.733296 -1.549908)
			(end 0.660908 -1.549908)
			(stroke
				(width 0.1524)
				(type default)
			)
			(layer "F.SilkS")
		)
		(fp_poly
			(pts
				(xy -2.4384 -1.20396) (xy -1.9304 -0.94996) (xy -2.4384 -0.69596)
			)
			(stroke
				(width 0)
				(type default)
			)
			(fill yes)
			(layer "F.SilkS")
		)
		(fp_line
			(start -0.849884 1.549908)
			(end 0.849884 1.549908)
			(stroke
				(width 0.1)
				(type default)
			)
			(layer "F.Fab")
		)
		(fp_line
			(start 0.849884 1.549908)
			(end 0.849884 -1.549908)
			(stroke
				(width 0.1)
				(type default)
			)
			(layer "F.Fab")
		)
		(fp_line
			(start -0.849884 -1.549908)
			(end -0.849884 1.549908)
			(stroke
				(width 0.1)
				(type default)
			)
			(layer "F.Fab")
		)
		(fp_line
			(start 0.849884 -1.549908)
			(end -0.849884 -1.549908)
			(stroke
				(width 0.1)
				(type default)
			)
			(layer "F.Fab")
		)
		(fp_poly
			(pts
				(xy -2.4384 -1.20396) (xy -2.4384 -0.69596) (xy -1.9304 -0.94996)
			)
			(stroke
				(width 0)
				(type default)
			)
			(fill yes)
			(layer "F.Fab")
		)
		(pad "1" smd rect
			(at -1.199896 -0.94996 180)
			(size 0.5588 0.8128)
			(layers "F.Cu" "F.Mask" "F.Paste")
			(net "FM_GPU_HSC_EN")
		)
		(pad "2" smd rect
			(at -1.199896 0 180)
			(size 0.5588 0.8128)
			(layers "F.Cu" "F.Mask" "F.Paste")
			(net "GPU_PRSNT_R")
		)
		(pad "3" smd rect
			(at -1.199896 0.94996 180)
			(size 0.5588 0.8128)
			(layers "F.Cu" "F.Mask" "F.Paste")
			(net "GND")
		)
		(pad "4" smd rect
			(at 1.199896 0.94996 180)
			(size 0.5588 0.8128)
			(layers "F.Cu" "F.Mask" "F.Paste")
			(net "FM_GPU_HSC_EN_BUF_R")
		)
		(pad "5" smd rect
			(at 1.199896 -0.94996 180)
			(size 0.5588 0.8128)
			(layers "F.Cu" "F.Mask" "F.Paste")
			(net "P3V3_AUX")
		)
	)
	(footprint ""
		(layer "F.Cu")
		(at 22.809454 -106.761026 180)
		(property "Reference" "R3668"
			(at 0 0 180)
			(layer "F.SilkS")
			(hide yes)
			(effects
				(font
					(size 1.27 1.27)
				)
			)
		)
		(property "Value" ""
			(at 0 0 180)
			(layer "F.Fab")
			(effects
				(font
					(size 1.27 1.27)
				)
			)
		)
		(duplicate_pad_numbers_are_jumpers no)
		(fp_line
			(start 0.7874 0.4064)
			(end -0.7874 0.4064)
			(stroke
				(width 0.1524)
				(type default)
			)
			(layer "F.SilkS")
		)
		(fp_line
			(start 0.7874 -0.4064)
			(end 0.7874 0.4064)
			(stroke
				(width 0.1524)
				(type default)
			)
			(layer "F.SilkS")
		)
		(fp_line
			(start -0.7874 0.4064)
			(end -0.7874 -0.4064)
			(stroke
				(width 0.1524)
				(type default)
			)
			(layer "F.SilkS")
		)
		(fp_line
			(start -0.7874 -0.4064)
			(end 0.7874 -0.4064)
			(stroke
				(width 0.1524)
				(type default)
			)
			(layer "F.SilkS")
		)
		(fp_line
			(start 0.67945 0.3048)
			(end 0.120396 0.3048)
			(stroke
				(width 0.1)
				(type default)
			)
			(layer "F.Fab")
		)
		(fp_line
			(start 0.67945 -0.3048)
			(end 0.67945 0.3048)
			(stroke
				(width 0.1)
				(type default)
			)
			(layer "F.Fab")
		)
		(fp_line
			(start 0.12065 -0.2794)
			(end 0.12065 -0.3048)
			(stroke
				(width 0.1)
				(type default)
			)
			(layer "F.Fab")
		)
		(fp_line
			(start 0.12065 -0.3048)
			(end 0.67945 -0.3048)
			(stroke
				(width 0.1)
				(type default)
			)
			(layer "F.Fab")
		)
		(fp_line
			(start 0.120396 0.3048)
			(end 0.120396 0.2794)
			(stroke
				(width 0.1)
				(type default)
			)
			(layer "F.Fab")
		)
		(fp_line
			(start 0.120396 0.2794)
			(end -0.12065 0.2794)
			(stroke
				(width 0.1)
				(type default)
			)
			(layer "F.Fab")
		)
		(fp_line
			(start -0.12065 0.3048)
			(end -0.67945 0.3048)
			(stroke
				(width 0.1)
				(type default)
			)
			(layer "F.Fab")
		)
		(fp_line
			(start -0.12065 0.2794)
			(end -0.12065 0.3048)
			(stroke
				(width 0.1)
				(type default)
			)
			(layer "F.Fab")
		)
		(fp_line
			(start -0.12065 -0.2794)
			(end 0.12065 -0.2794)
			(stroke
				(width 0.1)
				(type default)
			)
			(layer "F.Fab")
		)
		(fp_line
			(start -0.12065 -0.305054)
			(end -0.12065 -0.2794)
			(stroke
				(width 0.1)
				(type default)
			)
			(layer "F.Fab")
		)
		(fp_line
			(start -0.67945 0.3048)
			(end -0.67945 -0.305054)
			(stroke
				(width 0.1)
				(type default)
			)
			(layer "F.Fab")
		)
		(fp_line
			(start -0.67945 -0.305054)
			(end -0.12065 -0.305054)
			(stroke
				(width 0.1)
				(type default)
			)
			(layer "F.Fab")
		)
		(pad "1" smd circle
			(at -0.40005 0 180)
			(size 0 0)
			(layers "F.Cu" "F.Mask" "F.Paste")
			(net "ADC128_A1")
		)
		(pad "2" smd circle
			(at 0.40005 0 180)
			(size 0 0)
			(layers "F.Cu" "F.Mask" "F.Paste")
			(net "GND")
		)
	)
)
